(kicad_pcb
	(version 20260206)
	(generator "pcbnew")
	(generator_version "10.0")
	(general
		(thickness 1.6)
		(legacy_teardrops no)
	)
	(paper "A4")
	(title_block
		(title "v1-pdb — T6M_PDB_D_0927_0900.brd")
		(comment 1 "Open CloudServer (Microsoft) / footprints 205-209 of 321")
	)
	(layers
		(0 "F.Cu" signal "TOP")
		(4 "In1.Cu" signal "GND")
		(6 "In2.Cu" signal "IN1")
		(8 "In3.Cu" signal "VCC")
		(10 "In4.Cu" signal "VCC1")
		(12 "In5.Cu" signal "IN2")
		(14 "In6.Cu" signal "GND1")
		(2 "B.Cu" signal "BOTTOM")
		(9 "F.Adhes" user "F.Adhesive")
		(11 "B.Adhes" user "B.Adhesive")
		(13 "F.Paste" user "Package Geometry/Pastemask Top")
		(15 "B.Paste" user "Package Geometry/Pastemask Bottom")
		(5 "F.SilkS" user "Ref Des/Silkscreen Top")
		(7 "B.SilkS" user "Ref Des/Silkscreen Bottom")
		(1 "F.Mask" user "Board Geometry/Soldermask Top")
		(3 "B.Mask" user "Board Geometry/Soldermask Bottom")
		(17 "Dwgs.User" user "User.Drawings")
		(19 "Cmts.User" user "User.Comments")
		(21 "Eco1.User" user "User.Eco1")
		(23 "Eco2.User" user "User.Eco2")
		(25 "Edge.Cuts" user "Board Geometry/Outline")
		(27 "Margin" user)
		(31 "F.CrtYd" user "Package Geometry/Place Bound Top")
		(29 "B.CrtYd" user "Package Geometry/Place Bound Bottom")
		(35 "F.Fab" user "Ref Des/Assembly Top")
		(33 "B.Fab" user "Ref Des/Assembly Bottom")
	)
	(footprint ""
		(layer "F.Cu")
		(at 91.399868 -464.509866)
		(property "Reference" "H19"
			(at -5.1308 -5.23113 0)
			(unlocked yes)
			(layer "F.SilkS")
			(effects
				(font
					(size 0.7874 0.5842)
					(thickness 0.1524)
				)
				(justify left)
			)
		)
		(property "Value" ""
			(at 0 0 0)
			(layer "F.Fab")
			(effects
				(font
					(size 1.27 1.27)
				)
			)
		)
		(duplicate_pad_numbers_are_jumpers no)
		(fp_circle
			(center 0 0)
			(end 4.826 0)
			(stroke
				(width 0.1524)
				(type default)
			)
			(fill no)
			(layer "F.SilkS")
		)
		(fp_circle
			(center 0 0)
			(end 4.826 0)
			(stroke
				(width 0.1524)
				(type default)
			)
			(fill no)
			(layer "B.SilkS")
		)
		(fp_poly
			(pts
				(arc
					(start 0 4.0132)
					(mid 0 -4.0132)
					(end 0 4.0132)
				)
			)
			(stroke
				(width 0)
				(type default)
			)
			(fill no)
			(layer "F.CrtYd")
		)
		(pad "" np_thru_hole circle
			(at 0 0)
			(size 8.001 8.001)
			(drill 8.001)
			(layers "*.Cu" "*.Mask")
			(clearance 0.381)
			(thermal_gap 0.381)
		)
		(zone
			(layers "F.Cu" "B.Cu" "In1.Cu" "In2.Cu" "In3.Cu" "In4.Cu" "In5.Cu" "In6.Cu")
			(hatch none 0.5)
			(connect_pads
				(clearance 0)
			)
			(min_thickness 0.25)
			(keepout
				(tracks not_allowed)
				(vias allowed)
				(pads allowed)
				(copperpour not_allowed)
				(footprints allowed)
			)
			(placement
				(enabled no)
				(sheetname "")
			)
			(fill
				(thermal_gap 0.5)
				(thermal_bridge_width 0.5)
				(island_removal_mode 0)
			)
			(polygon
				(pts
					(arc
						(start 91.399868 -459.988666)
						(mid 91.399868 -469.031066)
						(end 91.399868 -459.988666)
					)
				)
			)
		)
	)
	(footprint ""
		(layer "F.Cu")
		(at 25.976072 -6.147562)
		(property "Reference" "R64"
			(at -3.764788 0.113792 0)
			(unlocked yes)
			(layer "F.SilkS")
			(effects
				(font
					(size 0.7874 0.5842)
					(thickness 0.1524)
				)
				(justify left)
			)
		)
		(property "Value" ""
			(at 0 0 0)
			(layer "F.Fab")
			(effects
				(font
					(size 1.27 1.27)
				)
			)
		)
		(duplicate_pad_numbers_are_jumpers no)
		(fp_line
			(start -0.7874 -0.4064)
			(end 0.7874 -0.4064)
			(stroke
				(width 0.1524)
				(type default)
			)
			(layer "F.SilkS")
		)
		(fp_line
			(start -0.7874 0.4064)
			(end -0.7874 -0.4064)
			(stroke
				(width 0.1524)
				(type default)
			)
			(layer "F.SilkS")
		)
		(fp_line
			(start 0.7874 -0.4064)
			(end 0.7874 0.4064)
			(stroke
				(width 0.1524)
				(type default)
			)
			(layer "F.SilkS")
		)
		(fp_line
			(start 0.7874 0.4064)
			(end -0.7874 0.4064)
			(stroke
				(width 0.1524)
				(type default)
			)
			(layer "F.SilkS")
		)
		(fp_poly
			(pts
				(xy -0.508 0.2794) (xy -0.508 0.2286) (xy -0.635 0.2286) (xy -0.635 -0.254) (xy -0.5334 -0.254)
				(xy -0.5334 -0.2794) (xy 0.5334 -0.2794) (xy 0.5334 -0.254) (xy 0.635 -0.254) (xy 0.635 0.254) (xy 0.5334 0.254)
				(xy 0.5334 0.2794)
			)
			(stroke
				(width 0)
				(type default)
			)
			(fill no)
			(layer "F.CrtYd")
		)
		(pad "1" smd rect
			(at 0.40005 0)
			(size 0.4572 0.508)
			(layers "F.Cu" "F.Mask" "F.Paste")
			(net "PSU1_RESET")
		)
		(pad "2" smd rect
			(at -0.40005 0)
			(size 0.4572 0.508)
			(layers "F.Cu" "F.Mask" "F.Paste")
			(net "P12V_STBY")
		)
	)
	(footprint ""
		(layer "F.Cu")
		(at 2.965958 -145.894298 90)
		(property "Reference" "R150"
			(at -0.783844 1.37795 90)
			(unlocked yes)
			(layer "F.SilkS")
			(effects
				(font
					(size 0.7874 0.5842)
					(thickness 0.1524)
				)
				(justify left)
			)
		)
		(property "Value" ""
			(at 0 0 90)
			(layer "F.Fab")
			(effects
				(font
					(size 1.27 1.27)
				)
			)
		)
		(duplicate_pad_numbers_are_jumpers no)
		(fp_line
			(start 0.7874 -0.4064)
			(end 0.7874 0.4064)
			(stroke
				(width 0.1524)
				(type default)
			)
			(layer "F.SilkS")
		)
		(fp_line
			(start -0.7874 -0.4064)
			(end 0.7874 -0.4064)
			(stroke
				(width 0.1524)
				(type default)
			)
			(layer "F.SilkS")
		)
		(fp_line
			(start 0.7874 0.4064)
			(end -0.7874 0.4064)
			(stroke
				(width 0.1524)
				(type default)
			)
			(layer "F.SilkS")
		)
		(fp_line
			(start -0.7874 0.4064)
			(end -0.7874 -0.4064)
			(stroke
				(width 0.1524)
				(type default)
			)
			(layer "F.SilkS")
		)
		(fp_poly
			(pts
				(xy -0.508 0.2794) (xy -0.508 0.2286) (xy -0.635 0.2286) (xy -0.635 -0.254) (xy -0.5334 -0.254)
				(xy -0.5334 -0.2794) (xy 0.5334 -0.2794) (xy 0.5334 -0.254) (xy 0.635 -0.254) (xy 0.635 0.254) (xy 0.5334 0.254)
				(xy 0.5334 0.2794)
			)
			(stroke
				(width 0)
				(type default)
			)
			(fill no)
			(layer "F.CrtYd")
		)
		(pad "1" smd rect
			(at 0.40005 0 90)
			(size 0.4572 0.508)
			(layers "F.Cu" "F.Mask" "F.Paste")
			(net "GND")
		)
		(pad "2" smd rect
			(at -0.40005 0 90)
			(size 0.4572 0.508)
			(layers "F.Cu" "F.Mask" "F.Paste")
			(net "N42130542")
		)
	)
	(footprint ""
		(layer "F.Cu")
		(at 11.444224 -461.694022)
		(property "Reference" "J20"
			(at -5.522214 -4.48056 0)
			(unlocked yes)
			(layer "F.SilkS")
			(effects
				(font
					(size 0.7874 0.5842)
					(thickness 0.1524)
				)
				(justify left)
			)
		)
		(property "Value" ""
			(at 0 0 0)
			(layer "F.Fab")
			(effects
				(font
					(size 1.27 1.27)
				)
			)
		)
		(duplicate_pad_numbers_are_jumpers no)
		(fp_line
			(start -8.949944 17.100042)
			(end -8.949944 20.699984)
			(stroke
				(width 0.1524)
				(type default)
			)
			(layer "F.SilkS")
		)
		(fp_line
			(start -8.949944 20.699984)
			(end -7.349998 20.699984)
			(stroke
				(width 0.1524)
				(type default)
			)
			(layer "F.SilkS")
		)
		(fp_line
			(start -7.349998 -3.299968)
			(end 2.450084 -3.299968)
			(stroke
				(width 0.1524)
				(type default)
			)
			(layer "F.SilkS")
		)
		(fp_line
			(start -7.349998 -2.899918)
			(end 2.450084 -2.899918)
			(stroke
				(width 0.1524)
				(type default)
			)
			(layer "F.SilkS")
		)
		(fp_line
			(start -7.349998 17.100042)
			(end -8.949944 17.100042)
			(stroke
				(width 0.1524)
				(type default)
			)
			(layer "F.SilkS")
		)
		(fp_line
			(start -7.349998 40.699944)
			(end -7.349998 -3.299968)
			(stroke
				(width 0.1524)
				(type default)
			)
			(layer "F.SilkS")
		)
		(fp_line
			(start -7.349998 41.099994)
			(end -7.349998 40.699944)
			(stroke
				(width 0.1524)
				(type default)
			)
			(layer "F.SilkS")
		)
		(fp_line
			(start 2.450084 -3.299968)
			(end 2.450084 -2.899918)
			(stroke
				(width 0.1524)
				(type default)
			)
			(layer "F.SilkS")
		)
		(fp_line
			(start 2.450084 -2.899918)
			(end 2.450084 40.699944)
			(stroke
				(width 0.1524)
				(type default)
			)
			(layer "F.SilkS")
		)
		(fp_line
			(start 2.450084 40.699944)
			(end -7.349998 40.699944)
			(stroke
				(width 0.1524)
				(type default)
			)
			(layer "F.SilkS")
		)
		(fp_line
			(start 2.450084 40.699944)
			(end 2.450084 41.099994)
			(stroke
				(width 0.1524)
				(type default)
			)
			(layer "F.SilkS")
		)
		(fp_line
			(start 2.450084 41.099994)
			(end -7.349998 41.099994)
			(stroke
				(width 0.1524)
				(type default)
			)
			(layer "F.SilkS")
		)
		(fp_poly
			(pts
				(xy 0.042418 -5.091176) (xy -1.227582 -5.091176) (xy -0.567182 -3.567176)
			)
			(stroke
				(width 0)
				(type default)
			)
			(fill yes)
			(layer "F.SilkS")
		)
		(fp_poly
			(pts
				(xy -7.349998 17.100042) (xy -8.949944 17.100042) (xy -8.949944 20.699984) (xy -7.349998 20.699984)
			)
			(stroke
				(width 0)
				(type default)
			)
			(fill yes)
			(layer "F.SilkS")
		)
		(fp_poly
			(pts
				(xy 1.0414 -1.0414) (xy -6.5278 -1.0414) (xy -6.5532 -1.0414) (xy -6.5532 38.8366) (xy -6.5278 38.8366)
				(xy 1.0414 38.8366)
			)
			(stroke
				(width 0)
				(type default)
			)
			(fill no)
			(layer "B.CrtYd")
		)
		(fp_poly
			(pts
				(xy -8.949944 17.100042) (xy -7.349998 17.100042) (xy -7.349998 -3.299968) (xy 2.450084 -3.299968)
				(xy 2.450084 41.099994) (xy -7.349998 41.099994) (xy -7.349998 20.699984) (xy -8.949944 20.699984)
			)
			(stroke
				(width 0)
				(type default)
			)
			(fill no)
			(layer "F.CrtYd")
		)
		(fp_line
			(start -8.949944 17.100042)
			(end -8.949944 20.699984)
			(stroke
				(width 0.1)
				(type default)
			)
			(layer "F.Fab")
		)
		(fp_line
			(start -8.949944 20.699984)
			(end -7.349998 20.699984)
			(stroke
				(width 0.1)
				(type default)
			)
			(layer "F.Fab")
		)
		(fp_line
			(start -7.349998 -3.299968)
			(end 2.450084 -3.299968)
			(stroke
				(width 0.1)
				(type default)
			)
			(layer "F.Fab")
		)
		(fp_line
			(start -7.349998 -2.899918)
			(end -7.349998 -3.299968)
			(stroke
				(width 0.1)
				(type default)
			)
			(layer "F.Fab")
		)
		(fp_line
			(start -7.349998 -2.899918)
			(end 2.44983 -2.899918)
			(stroke
				(width 0.1)
				(type default)
			)
			(layer "F.Fab")
		)
		(fp_line
			(start -7.349998 17.100042)
			(end -8.949944 17.100042)
			(stroke
				(width 0.1)
				(type default)
			)
			(layer "F.Fab")
		)
		(fp_line
			(start -7.349998 40.699944)
			(end -7.349998 -2.899918)
			(stroke
				(width 0.1)
				(type default)
			)
			(layer "F.Fab")
		)
		(fp_line
			(start -7.349998 41.099994)
			(end -7.349998 40.699944)
			(stroke
				(width 0.1)
				(type default)
			)
			(layer "F.Fab")
		)
		(fp_line
			(start 2.44983 -2.899918)
			(end 2.44983 40.699944)
			(stroke
				(width 0.1)
				(type default)
			)
			(layer "F.Fab")
		)
		(fp_line
			(start 2.44983 40.699944)
			(end -7.349998 40.699944)
			(stroke
				(width 0.1)
				(type default)
			)
			(layer "F.Fab")
		)
		(fp_line
			(start 2.450084 -3.299968)
			(end 2.450084 -2.899918)
			(stroke
				(width 0.1)
				(type default)
			)
			(layer "F.Fab")
		)
		(fp_line
			(start 2.450084 40.699944)
			(end 2.450084 41.099994)
			(stroke
				(width 0.1)
				(type default)
			)
			(layer "F.Fab")
		)
		(fp_line
			(start 2.450084 41.099994)
			(end -7.349998 41.099994)
			(stroke
				(width 0.1)
				(type default)
			)
			(layer "F.Fab")
		)
		(fp_poly
			(pts
				(xy 0.409956 -4.940808) (xy -0.860044 -4.940808) (xy -0.199644 -3.416808)
			)
			(stroke
				(width 0)
				(type default)
			)
			(fill yes)
			(layer "F.Fab")
		)
		(fp_text user "11"
			(at -9.198356 -0.33655 0)
			(unlocked yes)
			(layer "F.SilkS")
			(effects
				(font
					(size 0.7874 0.5842)
					(thickness 0.1524)
				)
				(justify left)
			)
		)
		(fp_text user "20"
			(at -6.240526 42.137076 0)
			(unlocked yes)
			(layer "F.SilkS")
			(effects
				(font
					(size 0.7874 0.5842)
					(thickness 0.1524)
				)
				(justify left)
			)
		)
		(fp_text user "1"
			(at -1.490218 -4.315714 0)
			(unlocked yes)
			(layer "F.SilkS")
			(effects
				(font
					(size 0.7874 0.5842)
					(thickness 0.1524)
				)
				(justify left)
			)
		)
		(fp_text user "10"
			(at -0.358902 42.337482 0)
			(unlocked yes)
			(layer "F.SilkS")
			(effects
				(font
					(size 0.7874 0.5842)
					(thickness 0.1524)
				)
				(justify left)
			)
		)
		(fp_text user "20"
			(at -5.506212 40.406574 270)
			(unlocked yes)
			(layer "B.SilkS")
			(effects
				(font
					(size 0.7874 0.5842)
					(thickness 0.1524)
				)
				(justify left mirror)
			)
		)
		(fp_text user "11"
			(at -5.279136 -2.356612 90)
			(unlocked yes)
			(layer "B.SilkS")
			(effects
				(font
					(size 0.7874 0.5842)
					(thickness 0.1524)
				)
				(justify left mirror)
			)
		)
		(fp_text user "10"
			(at -0.15875 40.350948 270)
			(unlocked yes)
			(layer "B.SilkS")
			(effects
				(font
					(size 0.7874 0.5842)
					(thickness 0.1524)
				)
				(justify left mirror)
			)
		)
		(fp_text user "1"
			(at 0.246126 -2.382012 90)
			(unlocked yes)
			(layer "B.SilkS")
			(effects
				(font
					(size 0.7874 0.5842)
					(thickness 0.1524)
				)
				(justify left mirror)
			)
		)
		(fp_text user "11"
			(at -5.506212 -1.086612 270)
			(unlocked yes)
			(layer "B.Fab")
			(effects
				(font
					(size 0.7874 0.5842)
					(thickness 0.000001)
				)
				(justify left mirror)
			)
		)
		(fp_text user "20"
			(at -5.506212 40.406574 270)
			(unlocked yes)
			(layer "B.Fab")
			(effects
				(font
					(size 0.7874 0.5842)
					(thickness 0.000001)
				)
				(justify left mirror)
			)
		)
		(fp_text user "10"
			(at -0.15875 40.350948 270)
			(unlocked yes)
			(layer "B.Fab")
			(effects
				(font
					(size 0.7874 0.5842)
					(thickness 0.000001)
				)
				(justify left mirror)
			)
		)
		(fp_text user "1"
			(at 0.01905 -1.112012 270)
			(unlocked yes)
			(layer "B.Fab")
			(effects
				(font
					(size 0.7874 0.5842)
					(thickness 0.000001)
				)
				(justify left mirror)
			)
		)
		(fp_text user "20"
			(at -5.506212 41.264332 270)
			(unlocked yes)
			(layer "F.Fab")
			(effects
				(font
					(size 0.7874 0.5842)
					(thickness 0.000001)
				)
				(justify left)
			)
		)
		(fp_text user "11"
			(at -5.455412 -4.713224 270)
			(unlocked yes)
			(layer "F.Fab")
			(effects
				(font
					(size 0.7874 0.5842)
					(thickness 0.000001)
				)
				(justify left)
			)
		)
		(fp_text user "10"
			(at -0.183896 41.102534 270)
			(unlocked yes)
			(layer "F.Fab")
			(effects
				(font
					(size 0.7874 0.5842)
					(thickness 0.000001)
				)
				(justify left)
			)
		)
		(fp_text user "1"
			(at 0.53086 -3.95732 270)
			(unlocked yes)
			(layer "F.Fab")
			(effects
				(font
					(size 0.7874 0.5842)
					(thickness 0.000001)
				)
				(justify left)
			)
		)
		(pad "1" thru_hole rect
			(at 0 0 270)
			(size 1.9558 1.9558)
			(drill 1.4478)
			(layers "*.Cu" "*.Mask")
			(remove_unused_layers no)
			(net "FAN1_TACH")
			(clearance 0)
			(padstack
				(mode front_inner_back)
				(layer "Inner"
					(shape circle)
					(size 1.9558 1.9558)
					(clearance 0)
				)
				(layer "B.Cu"
					(shape rect)
					(size 1.9558 1.9558)
					(clearance 0)
				)
			)
		)
		(pad "2" thru_hole circle
			(at 0 4.19989 270)
			(size 1.9558 1.9558)
			(drill 1.4478)
			(layers "*.Cu" "*.Mask")
			(remove_unused_layers no)
			(net "P12V")
			(clearance 0)
		)
		(pad "3" thru_hole circle
			(at 0 8.400034 270)
			(size 1.9558 1.9558)
			(drill 1.4478)
			(layers "*.Cu" "*.Mask")
			(remove_unused_layers no)
			(net "P12V")
			(clearance 0)
		)
		(pad "4" thru_hole circle
			(at 0 12.599924 270)
			(size 1.9558 1.9558)
			(drill 1.4478)
			(layers "*.Cu" "*.Mask")
			(remove_unused_layers no)
			(net "FAN2_TACH")
			(clearance 0)
		)
		(pad "5" thru_hole circle
			(at 0 16.800068 270)
			(size 1.9558 1.9558)
			(drill 1.4478)
			(layers "*.Cu" "*.Mask")
			(remove_unused_layers no)
			(net "P12V")
			(clearance 0)
		)
		(pad "6" thru_hole circle
			(at 0 20.999958 270)
			(size 1.9558 1.9558)
			(drill 1.4478)
			(layers "*.Cu" "*.Mask")
			(remove_unused_layers no)
			(net "P12V")
			(clearance 0)
		)
		(pad "7" thru_hole circle
			(at 0 25.200102 270)
			(size 1.9558 1.9558)
			(drill 1.4478)
			(layers "*.Cu" "*.Mask")
			(remove_unused_layers no)
			(net "FAN3_TACH")
			(clearance 0)
		)
		(pad "8" thru_hole circle
			(at 0 29.399992 270)
			(size 1.9558 1.9558)
			(drill 1.4478)
			(layers "*.Cu" "*.Mask")
			(remove_unused_layers no)
			(net "P12V")
			(clearance 0)
		)
		(pad "9" thru_hole circle
			(at 0 33.599882 270)
			(size 1.9558 1.9558)
			(drill 1.4478)
			(layers "*.Cu" "*.Mask")
			(remove_unused_layers no)
			(net "P12V")
			(clearance 0)
		)
		(pad "10" thru_hole circle
			(at 0 37.800026 270)
			(size 1.9558 1.9558)
			(drill 1.4478)
			(layers "*.Cu" "*.Mask")
			(remove_unused_layers no)
			(net "FAN4_TACH")
			(clearance 0)
		)
		(pad "11" thru_hole circle
			(at -5.500116 0 270)
			(size 1.9558 1.9558)
			(drill 1.4478)
			(layers "*.Cu" "*.Mask")
			(remove_unused_layers no)
			(net "FAN5_TACH")
			(clearance 0)
		)
		(pad "12" thru_hole circle
			(at -5.500116 4.19989 270)
			(size 1.9558 1.9558)
			(drill 1.4478)
			(layers "*.Cu" "*.Mask")
			(remove_unused_layers no)
			(net "GND")
			(clearance 0)
		)
		(pad "13" thru_hole circle
			(at -5.500116 8.400034 270)
			(size 1.9558 1.9558)
			(drill 1.4478)
			(layers "*.Cu" "*.Mask")
			(remove_unused_layers no)
			(net "GND")
			(clearance 0)
		)
		(pad "14" thru_hole circle
			(at -5.500116 12.599924 270)
			(size 1.9558 1.9558)
			(drill 1.4478)
			(layers "*.Cu" "*.Mask")
			(remove_unused_layers no)
			(net "FAN6_TACH")
			(clearance 0)
		)
		(pad "15" thru_hole circle
			(at -5.500116 16.800068 270)
			(size 1.9558 1.9558)
			(drill 1.4478)
			(layers "*.Cu" "*.Mask")
			(remove_unused_layers no)
			(net "GND")
			(clearance 0)
		)
		(pad "16" thru_hole circle
			(at -5.500116 20.999958 270)
			(size 1.9558 1.9558)
			(drill 1.4478)
			(layers "*.Cu" "*.Mask")
			(remove_unused_layers no)
			(net "GND")
			(clearance 0)
		)
		(pad "17" thru_hole circle
			(at -5.500116 25.200102 270)
			(size 1.9558 1.9558)
			(drill 1.4478)
			(layers "*.Cu" "*.Mask")
			(remove_unused_layers no)
			(net "FAN_PWM")
			(clearance 0)
		)
		(pad "18" thru_hole circle
			(at -5.500116 29.399992 270)
			(size 1.9558 1.9558)
			(drill 1.4478)
			(layers "*.Cu" "*.Mask")
			(remove_unused_layers no)
			(net "GND")
			(clearance 0)
		)
		(pad "19" thru_hole circle
			(at -5.500116 33.599882 270)
			(size 1.9558 1.9558)
			(drill 1.4478)
			(layers "*.Cu" "*.Mask")
			(remove_unused_layers no)
			(net "GND")
			(clearance 0)
		)
		(pad "20" thru_hole circle
			(at -5.500116 37.800026 270)
			(size 1.9558 1.9558)
			(drill 1.4478)
			(layers "*.Cu" "*.Mask")
			(remove_unused_layers no)
			(net "FAN_PWM")
			(clearance 0)
		)
	)
	(footprint ""
		(layer "F.Cu")
		(at 46.430692 -238.246666 180)
		(property "Reference" "R88"
			(at 4.272788 0.078232 0)
			(unlocked yes)
			(layer "F.SilkS")
			(effects
				(font
					(size 0.7874 0.5842)
					(thickness 0.1524)
				)
				(justify left)
			)
		)
		(property "Value" ""
			(at 0 0 180)
			(layer "F.Fab")
			(effects
				(font
					(size 1.27 1.27)
				)
			)
		)
		(duplicate_pad_numbers_are_jumpers no)
		(fp_line
			(start 0.7874 0.4064)
			(end -0.7874 0.4064)
			(stroke
				(width 0.1524)
				(type default)
			)
			(layer "F.SilkS")
		)
		(fp_line
			(start 0.7874 -0.4064)
			(end 0.7874 0.4064)
			(stroke
				(width 0.1524)
				(type default)
			)
			(layer "F.SilkS")
		)
		(fp_line
			(start -0.7874 0.4064)
			(end -0.7874 -0.4064)
			(stroke
				(width 0.1524)
				(type default)
			)
			(layer "F.SilkS")
		)
		(fp_line
			(start -0.7874 -0.4064)
			(end 0.7874 -0.4064)
			(stroke
				(width 0.1524)
				(type default)
			)
			(layer "F.SilkS")
		)
		(fp_poly
			(pts
				(xy -0.508 0.2794) (xy -0.508 0.2286) (xy -0.635 0.2286) (xy -0.635 -0.254) (xy -0.5334 -0.254)
				(xy -0.5334 -0.2794) (xy 0.5334 -0.2794) (xy 0.5334 -0.254) (xy 0.635 -0.254) (xy 0.635 0.254) (xy 0.5334 0.254)
				(xy 0.5334 0.2794)
			)
			(stroke
				(width 0)
				(type default)
			)
			(fill no)
			(layer "F.CrtYd")
		)
		(pad "1" smd rect
			(at 0.40005 0 180)
			(size 0.4572 0.508)
			(layers "F.Cu" "F.Mask" "F.Paste")
			(net "PSU1_REMOTE_R_P")
		)
		(pad "2" smd rect
			(at -0.40005 0 180)
			(size 0.4572 0.508)
			(layers "F.Cu" "F.Mask" "F.Paste")
			(net "P12V")
		)
	)
)
